# BASEBOARD_FAB2 (Tioga Pass) — schematic netlist excerpt (pin names and nets, part order shuffled) for the footprints in the layout excerpt that follows; sources: Cadence DE-HDL packaged netlist, KiCad conversion of Wiwynn_Tioga_Pass_MB.brd

T1P10  TPAD-DIFF-4P-GP  pkg DISCRET-GB3  page 256
  \1\  = L10_73OHM_6INCH_DP
  \2\  = L10_73OHM_6INCH_DN
  GND1  = GND
  GND2  = GND

C1E12  CAP  10UF 16V 10% X6S  pkg 0805  page 195 : A = P12V_PSU ; B = GND
R9F30  RES  4.75K 1% CHIP  pkg 0402  page 177 : A = P3V3_STBY ; B = FM_BMC_FAULT_LED_N

(kicad_pcb
	(version 20260206)
	(generator "pcbnew")
	(generator_version "10.0")
	(general
		(thickness 1.6)
		(legacy_teardrops no)
	)
	(paper "A4")
	(title_block
		(title "Wiwynn_Tioga_Pass_MB.brd")
		(comment 1 "Tioga Pass / footprints 715-717 of 4770")
	)
	(layers
		(0 "F.Cu" signal "TOP")
		(4 "In1.Cu" signal "L2GND")
		(6 "In2.Cu" signal "L3")
		(8 "In3.Cu" signal "L4GND")
		(10 "In4.Cu" signal "L5")
		(12 "In5.Cu" signal "L6GND")
		(14 "In6.Cu" signal "L7VCC")
		(16 "In7.Cu" signal "L8VCC")
		(18 "In8.Cu" signal "L9GND")
		(20 "In9.Cu" signal "L10")
		(22 "In10.Cu" signal "L11GND")
		(24 "In11.Cu" signal "L12")
		(26 "In12.Cu" signal "L13GND")
		(2 "B.Cu" signal "BOTTOM")
		(9 "F.Adhes" user "F.Adhesive")
		(11 "B.Adhes" user "B.Adhesive")
		(13 "F.Paste" user "Package Geometry/Pastemask Top")
		(15 "B.Paste" user "Package Geometry/Pastemask Bottom")
		(5 "F.SilkS" user "Ref Des/Silkscreen Top")
		(7 "B.SilkS" user "Ref Des/Silkscreen Bottom")
		(1 "F.Mask" user "Board Geometry/Soldermask Top")
		(3 "B.Mask" user "Board Geometry/Soldermask Bottom")
		(17 "Dwgs.User" user "User.Drawings")
		(19 "Cmts.User" user "User.Comments")
		(21 "Eco1.User" user "User.Eco1")
		(23 "Eco2.User" user "User.Eco2")
		(25 "Edge.Cuts" user "Board Geometry/Outline")
		(27 "Margin" user)
		(31 "F.CrtYd" user "Package Geometry/Place Bound Top")
		(29 "B.CrtYd" user "Package Geometry/Place Bound Bottom")
		(35 "F.Fab" user "Ref Des/Assembly Top")
		(33 "B.Fab" user "Ref Des/Assembly Bottom")
	)
	(footprint ""
		(layer "F.Cu")
		(at 458.39888 -26.17978 180)
		(property "Reference" "R9F30"
			(at 0 0 180)
			(layer "F.SilkS")
			(hide yes)
			(effects
				(font
					(size 1.27 1.27)
				)
			)
		)
		(property "Value" ""
			(at 0 0 180)
			(layer "F.Fab")
			(effects
				(font
					(size 1.27 1.27)
				)
			)
		)
		(duplicate_pad_numbers_are_jumpers no)
		(fp_poly
			(pts
				(xy -0.2794 -0.1016) (xy 0.2794 -0.1016) (xy 0.2794 0.9906) (xy -0.2794 0.9906)
			)
			(stroke
				(width 0)
				(type default)
			)
			(fill no)
			(layer "F.CrtYd")
		)
		(fp_line
			(start 0.2794 0.9906)
			(end 0.2794 -0.1016)
			(stroke
				(width 0.1)
				(type default)
			)
			(layer "F.Fab")
		)
		(fp_line
			(start 0.2794 -0.1016)
			(end -0.2794 -0.1016)
			(stroke
				(width 0.1)
				(type default)
			)
			(layer "F.Fab")
		)
		(fp_line
			(start -0.2794 0.9906)
			(end 0.2794 0.9906)
			(stroke
				(width 0.1)
				(type default)
			)
			(layer "F.Fab")
		)
		(fp_line
			(start -0.2794 -0.1016)
			(end -0.2794 0.9906)
			(stroke
				(width 0.1)
				(type default)
			)
			(layer "F.Fab")
		)
		(pad "1" smd rect
			(at 0 0 180)
			(size 0.508 0.508)
			(layers "F.Cu" "F.Mask" "F.Paste")
			(net "P3V3_STBY")
		)
		(pad "2" smd rect
			(at 0 0.889 180)
			(size 0.508 0.508)
			(layers "F.Cu" "F.Mask" "F.Paste")
			(net "FM_BMC_FAULT_LED_N")
		)
		(zone
			(layer "F.Cu")
			(hatch none 0.5)
			(connect_pads
				(clearance 0)
			)
			(min_thickness 0.25)
			(keepout
				(tracks not_allowed)
				(vias allowed)
				(pads allowed)
				(copperpour not_allowed)
				(footprints allowed)
			)
			(placement
				(enabled no)
				(sheetname "")
			)
			(fill
				(thermal_gap 0.5)
				(thermal_bridge_width 0.5)
				(island_removal_mode 0)
			)
			(polygon
				(pts
					(xy 458.65288 -26.81478) (xy 458.14488 -26.81478) (xy 458.14488 -26.43378) (xy 458.65288 -26.43378)
				)
			)
		)
		(zone
			(layer "F.Cu")
			(hatch none 0.5)
			(connect_pads
				(clearance 0)
			)
			(min_thickness 0.25)
			(keepout
				(tracks allowed)
				(vias not_allowed)
				(pads allowed)
				(copperpour not_allowed)
				(footprints allowed)
			)
			(placement
				(enabled no)
				(sheetname "")
			)
			(fill
				(thermal_gap 0.5)
				(thermal_bridge_width 0.5)
				(island_removal_mode 0)
			)
			(polygon
				(pts
					(xy 458.65288 -26.43378) (xy 458.14488 -26.43378) (xy 458.14488 -26.81478) (xy 458.65288 -26.81478)
				)
			)
		)
	)
	(footprint ""
		(layer "F.Cu")
		(at 132.650484 12.014454 -90)
		(property "Reference" "T1P10"
			(at 0 0 270)
			(layer "F.SilkS")
			(hide yes)
			(effects
				(font
					(size 1.27 1.27)
				)
			)
		)
		(property "Value" "*"
			(at -3.302 1.12395 270)
			(unlocked yes)
			(layer "F.Fab")
			(hide yes)
			(effects
				(font
					(size 0.889 0.889)
					(thickness 0.1524)
				)
			)
		)
		(property "Device Type" "TPAD-DIFF-4P-GP_DISCRET-GB3-TPA"
			(at -3.302 -0.40005 270)
			(unlocked yes)
			(layer "F.Fab")
			(hide yes)
			(effects
				(font
					(size 0.889 0.889)
					(thickness 0.1524)
				)
			)
		)
		(duplicate_pad_numbers_are_jumpers no)
		(fp_line
			(start -2.286 2.286)
			(end 2.286 2.286)
			(stroke
				(width 0.1524)
				(type default)
			)
			(layer "F.SilkS")
		)
		(fp_line
			(start 2.286 2.286)
			(end 2.286 -2.286)
			(stroke
				(width 0.1524)
				(type default)
			)
			(layer "F.SilkS")
		)
		(fp_line
			(start -2.286 -2.286)
			(end -2.286 2.286)
			(stroke
				(width 0.1524)
				(type default)
			)
			(layer "F.SilkS")
		)
		(fp_line
			(start 2.286 -2.286)
			(end -2.286 -2.286)
			(stroke
				(width 0.1524)
				(type default)
			)
			(layer "F.SilkS")
		)
		(fp_line
			(start -2.413 -2.413)
			(end -2.413 -1.143)
			(stroke
				(width 0.4064)
				(type default)
			)
			(layer "F.SilkS")
		)
		(fp_line
			(start -1.143 -2.413)
			(end -2.413 -2.413)
			(stroke
				(width 0.4064)
				(type default)
			)
			(layer "F.SilkS")
		)
		(fp_rect
			(start -2.54 2.54)
			(end 2.54 -2.54)
			(stroke
				(width 0)
				(type default)
			)
			(fill no)
			(layer "F.CrtYd")
		)
		(fp_rect
			(start -2.54 2.54)
			(end 2.54 -2.54)
			(stroke
				(width 0)
				(type default)
			)
			(fill no)
			(layer "F.Fab")
		)
		(pad "1" thru_hole circle
			(at -1.27 -1.27 270)
			(size 1.524 1.524)
			(drill 0.9144)
			(layers "*.Cu" "*.Mask")
			(remove_unused_layers no)
			(net "L10_73OHM_6INCH_DP")
			(clearance -0.0508)
			(thermal_gap 0.127)
			(padstack
				(mode front_inner_back)
				(layer "Inner"
					(shape circle)
					(size 1.1684 1.1684)
					(clearance 0.127)
				)
				(layer "B.Cu"
					(shape circle)
					(size 1.524 1.524)
					(clearance -0.0508)
				)
			)
		)
		(pad "2" thru_hole circle
			(at 1.27 -1.27 270)
			(size 1.524 1.524)
			(drill 0.9144)
			(layers "*.Cu" "*.Mask")
			(remove_unused_layers no)
			(net "L10_73OHM_6INCH_DN")
			(clearance -0.0508)
			(thermal_gap 0.127)
			(padstack
				(mode front_inner_back)
				(layer "Inner"
					(shape circle)
					(size 1.1684 1.1684)
					(clearance 0.127)
				)
				(layer "B.Cu"
					(shape circle)
					(size 1.524 1.524)
					(clearance -0.0508)
				)
			)
		)
		(pad "GND1" thru_hole rect
			(at -1.27 1.27 270)
			(size 1.524 1.524)
			(drill 0.9144)
			(layers "*.Cu" "*.Mask")
			(remove_unused_layers no)
			(net "GND")
			(clearance -0.0508)
			(thermal_gap 0.127)
			(padstack
				(mode front_inner_back)
				(layer "Inner"
					(shape circle)
					(size 1.1684 1.1684)
					(clearance 0.127)
				)
				(layer "B.Cu"
					(shape rect)
					(size 1.524 1.524)
					(clearance -0.0508)
				)
			)
		)
		(pad "GND2" thru_hole rect
			(at 1.27 1.27 270)
			(size 1.524 1.524)
			(drill 0.9144)
			(layers "*.Cu" "*.Mask")
			(remove_unused_layers no)
			(net "GND")
			(clearance -0.0508)
			(thermal_gap 0.127)
			(padstack
				(mode front_inner_back)
				(layer "Inner"
					(shape circle)
					(size 1.1684 1.1684)
					(clearance 0.127)
				)
				(layer "B.Cu"
					(shape rect)
					(size 1.524 1.524)
					(clearance -0.0508)
				)
			)
		)
	)
	(footprint ""
		(layer "F.Cu")
		(at 13.716 -54.917848 90)
		(property "Reference" "C1E12"
			(at 0 0 90)
			(layer "F.SilkS")
			(hide yes)
			(effects
				(font
					(size 1.27 1.27)
				)
			)
		)
		(property "Value" ""
			(at 0 0 90)
			(layer "F.Fab")
			(effects
				(font
					(size 1.27 1.27)
				)
			)
		)
		(duplicate_pad_numbers_are_jumpers no)
		(fp_rect
			(start 0.7239 -0.2159)
			(end -0.7239 1.9939)
			(stroke
				(width 0)
				(type default)
			)
			(fill no)
			(layer "F.CrtYd")
		)
		(fp_line
			(start 0.7239 -0.2159)
			(end -0.7239 -0.2159)
			(stroke
				(width 0.1)
				(type default)
			)
			(layer "F.Fab")
		)
		(fp_line
			(start -0.7239 -0.2159)
			(end -0.7239 1.9939)
			(stroke
				(width 0.1)
				(type default)
			)
			(layer "F.Fab")
		)
		(fp_line
			(start 0.7239 1.9939)
			(end 0.7239 -0.2159)
			(stroke
				(width 0.1)
				(type default)
			)
			(layer "F.Fab")
		)
		(fp_line
			(start -0.7239 1.9939)
			(end 0.7239 1.9939)
			(stroke
				(width 0.1)
				(type default)
			)
			(layer "F.Fab")
		)
		(pad "1" smd rect
			(at 0 0 90)
			(size 1.27 1.016)
			(layers "F.Cu" "F.Mask" "F.Paste")
			(net "P12V_PSU")
		)
		(pad "2" smd rect
			(at 0 1.778 90)
			(size 1.27 1.016)
			(layers "F.Cu" "F.Mask" "F.Paste")
			(net "GND")
		)
		(zone
			(layer "F.Cu")
			(hatch none 0.5)
			(connect_pads
				(clearance 0)
			)
			(min_thickness 0.25)
			(keepout
				(tracks not_allowed)
				(vias allowed)
				(pads allowed)
				(copperpour not_allowed)
				(footprints allowed)
			)
			(placement
				(enabled no)
				(sheetname "")
			)
			(fill
				(thermal_gap 0.5)
				(thermal_bridge_width 0.5)
				(island_removal_mode 0)
			)
			(polygon
				(pts
					(xy 14.224 -55.552848) (xy 14.224 -54.282848) (xy 14.986 -54.282848) (xy 14.986 -55.552848)
				)
			)
		)
	)
)
